(kicad_pcb
	(version 20241229)
	(generator "pcbnew")
	(generator_version "9.0")
	(general
		(thickness 1.294)
		(legacy_teardrops no)
	)
	(paper "A3")
	(title_block
		(title "Kintex 410T devboard")
		(date "2024-04-03")
		(rev "1.1.2")
		(comment 9 "footprints 812-817 of 975")
	)
	(layers
		(0 "F.Cu" mixed)
		(4 "In1.Cu" power)
		(6 "In2.Cu" power)
		(8 "In3.Cu" mixed)
		(10 "In4.Cu" power)
		(12 "In5.Cu" mixed)
		(14 "In6.Cu" power)
		(16 "In7.Cu" mixed)
		(18 "In8.Cu" power)
		(2 "B.Cu" mixed)
		(9 "F.Adhes" user "F.Adhesive")
		(11 "B.Adhes" user "B.Adhesive")
		(13 "F.Paste" user)
		(15 "B.Paste" user)
		(5 "F.SilkS" user "F.Silkscreen")
		(7 "B.SilkS" user "B.Silkscreen")
		(1 "F.Mask" user)
		(3 "B.Mask" user)
		(17 "Dwgs.User" user "User.Drawings")
		(19 "Cmts.User" user "User.Comments")
		(21 "Eco1.User" user "User.Eco1")
		(23 "Eco2.User" user "User.Eco2")
		(25 "Edge.Cuts" user)
		(27 "Margin" user)
		(31 "F.CrtYd" user "F.Courtyard")
		(29 "B.CrtYd" user "B.Courtyard")
		(35 "F.Fab" user)
		(33 "B.Fab" user)
	)
	(footprint "antmicro-footprints:C_0402_1005Metric"
		(layer "B.Cu")
		(at 198.325 134.175 180)
		(descr "Capacitor SMD 0402")
		(tags "capacitor SMD 0402")
		(property "Reference" "C53"
			(at -26.025 28.1 0)
			(layer "B.SilkS")
			(effects
				(font
					(size 0.7 0.7)
					(thickness 0.15)
				)
				(justify left bottom mirror)
			)
		)
		(property "Value" "C_100n_0402"
			(at 0 -1.169 0)
			(layer "B.Fab")
			(effects
				(font
					(size 0.7 0.7)
					(thickness 0.15)
				)
				(justify left bottom mirror)
			)
		)
		(property "Description" "SMD Multilayer Ceramic Capacitor, 0.1 µF, 50 V, 0402 [1005 Metric], ± 10%, X5R, GRM Series"
			(at 0 0 180)
			(layer "F.Fab")
			(hide yes)
			(effects
				(font
					(size 1.27 1.27)
					(thickness 0.15)
				)
			)
		)
		(property "Author" "Antmicro"
			(at 396.65 268.35 0)
			(layer "B.Fab")
			(hide yes)
			(effects
				(font
					(size 1 1)
					(thickness 0.15)
				)
				(justify mirror)
			)
		)
		(property "Dielectric" "X5R"
			(at 396.65 268.35 0)
			(layer "B.Fab")
			(hide yes)
			(effects
				(font
					(size 1 1)
					(thickness 0.15)
				)
				(justify mirror)
			)
		)
		(property "License" "Apache-2.0"
			(at 396.65 268.35 0)
			(layer "B.Fab")
			(hide yes)
			(effects
				(font
					(size 1 1)
					(thickness 0.15)
				)
				(justify mirror)
			)
		)
		(property "MPN" "GRM155R61H104KE14D"
			(at 396.65 268.35 0)
			(layer "B.Fab")
			(hide yes)
			(effects
				(font
					(size 1 1)
					(thickness 0.15)
				)
				(justify mirror)
			)
		)
		(property "Manufacturer" "Murata"
			(at 396.65 268.35 0)
			(layer "B.Fab")
			(hide yes)
			(effects
				(font
					(size 1 1)
					(thickness 0.15)
				)
				(justify mirror)
			)
		)
		(property "Val" "100n"
			(at 396.65 268.35 0)
			(layer "B.Fab")
			(hide yes)
			(effects
				(font
					(size 1 1)
					(thickness 0.15)
				)
				(justify mirror)
			)
		)
		(property "Voltage" "50V"
			(at 396.65 268.35 0)
			(layer "B.Fab")
			(hide yes)
			(effects
				(font
					(size 1 1)
					(thickness 0.15)
				)
				(justify mirror)
			)
		)
		(sheetname "FPGA supply")
		(sheetfile "fpga-supply.kicad_sch")
		(attr smd)
		(fp_rect
			(start -0.925 0.47)
			(end 0.925 -0.47)
			(stroke
				(width 0.05)
				(type default)
			)
			(fill no)
			(layer "B.CrtYd")
		)
		(fp_line
			(start 0.504 0.25)
			(end 0.504 -0.248)
			(stroke
				(width 0.15)
				(type solid)
			)
			(layer "B.Fab")
		)
		(fp_line
			(start 0.504 -0.248)
			(end -0.494 -0.248)
			(stroke
				(width 0.15)
				(type solid)
			)
			(layer "B.Fab")
		)
		(fp_line
			(start -0.494 0.25)
			(end 0.504 0.25)
			(stroke
				(width 0.15)
				(type solid)
			)
			(layer "B.Fab")
		)
		(fp_line
			(start -0.494 -0.248)
			(end -0.494 0.25)
			(stroke
				(width 0.15)
				(type solid)
			)
			(layer "B.Fab")
		)
		(pad "1" smd roundrect
			(at -0.48 0 180)
			(size 0.59 0.64)
			(layers "B.Cu" "B.Mask" "B.Paste")
			(roundrect_rratio 0.25)
			(net 1 "GND")
			(pintype "passive")
		)
		(pad "2" smd roundrect
			(at 0.48 0 180)
			(size 0.59 0.64)
			(layers "B.Cu" "B.Mask" "B.Paste")
			(roundrect_rratio 0.25)
			(net 26 "+1V8")
			(pintype "passive")
		)
	)
	(footprint "antmicro-footprints:C_0402_1005Metric"
		(layer "B.Cu")
		(at 202 137.5 180)
		(descr "Capacitor SMD 0402")
		(tags "capacitor SMD 0402")
		(property "Reference" "C69"
			(at -1.1 -1.225 0)
			(layer "B.SilkS")
			(effects
				(font
					(size 0.7 0.7)
					(thickness 0.15)
				)
				(justify left bottom mirror)
			)
		)
		(property "Value" "C_100n_0402"
			(at 0 -1.169 0)
			(layer "B.Fab")
			(effects
				(font
					(size 0.7 0.7)
					(thickness 0.15)
				)
				(justify left bottom mirror)
			)
		)
		(property "Description" "SMD Multilayer Ceramic Capacitor, 0.1 µF, 50 V, 0402 [1005 Metric], ± 10%, X5R, GRM Series"
			(at 0 0 180)
			(layer "F.Fab")
			(hide yes)
			(effects
				(font
					(size 1.27 1.27)
					(thickness 0.15)
				)
			)
		)
		(property "Author" "Antmicro"
			(at 404 275 0)
			(layer "B.Fab")
			(hide yes)
			(effects
				(font
					(size 1 1)
					(thickness 0.15)
				)
				(justify mirror)
			)
		)
		(property "Dielectric" "X5R"
			(at 404 275 0)
			(layer "B.Fab")
			(hide yes)
			(effects
				(font
					(size 1 1)
					(thickness 0.15)
				)
				(justify mirror)
			)
		)
		(property "License" "Apache-2.0"
			(at 404 275 0)
			(layer "B.Fab")
			(hide yes)
			(effects
				(font
					(size 1 1)
					(thickness 0.15)
				)
				(justify mirror)
			)
		)
		(property "MPN" "GRM155R61H104KE14D"
			(at 404 275 0)
			(layer "B.Fab")
			(hide yes)
			(effects
				(font
					(size 1 1)
					(thickness 0.15)
				)
				(justify mirror)
			)
		)
		(property "Manufacturer" "Murata"
			(at 404 275 0)
			(layer "B.Fab")
			(hide yes)
			(effects
				(font
					(size 1 1)
					(thickness 0.15)
				)
				(justify mirror)
			)
		)
		(property "Val" "100n"
			(at 404 275 0)
			(layer "B.Fab")
			(hide yes)
			(effects
				(font
					(size 1 1)
					(thickness 0.15)
				)
				(justify mirror)
			)
		)
		(property "Voltage" "50V"
			(at 404 275 0)
			(layer "B.Fab")
			(hide yes)
			(effects
				(font
					(size 1 1)
					(thickness 0.15)
				)
				(justify mirror)
			)
		)
		(sheetname "FPGA Bank 18 & 32")
		(sheetfile "fpga-bank-18-32.kicad_sch")
		(attr smd)
		(fp_rect
			(start -0.925 0.47)
			(end 0.925 -0.47)
			(stroke
				(width 0.05)
				(type default)
			)
			(fill no)
			(layer "B.CrtYd")
		)
		(fp_line
			(start 0.504 0.25)
			(end 0.504 -0.248)
			(stroke
				(width 0.15)
				(type solid)
			)
			(layer "B.Fab")
		)
		(fp_line
			(start 0.504 -0.248)
			(end -0.494 -0.248)
			(stroke
				(width 0.15)
				(type solid)
			)
			(layer "B.Fab")
		)
		(fp_line
			(start -0.494 0.25)
			(end 0.504 0.25)
			(stroke
				(width 0.15)
				(type solid)
			)
			(layer "B.Fab")
		)
		(fp_line
			(start -0.494 -0.248)
			(end -0.494 0.25)
			(stroke
				(width 0.15)
				(type solid)
			)
			(layer "B.Fab")
		)
		(pad "1" smd roundrect
			(at -0.48 0 180)
			(size 0.59 0.64)
			(layers "B.Cu" "B.Mask" "B.Paste")
			(roundrect_rratio 0.25)
			(net 1 "GND")
			(pintype "passive")
		)
		(pad "2" smd roundrect
			(at 0.48 0 180)
			(size 0.59 0.64)
			(layers "B.Cu" "B.Mask" "B.Paste")
			(roundrect_rratio 0.25)
			(net 26 "+1V8")
			(pintype "passive")
		)
	)
	(footprint "antmicro-footprints:R_0402_1005Metric"
		(layer "B.Cu")
		(at 227.1 154.2 180)
		(descr "Resistor SMD 0402")
		(tags "resistor SMD 0402")
		(property "Reference" "R224"
			(at 0.725 -0.375 0)
			(layer "B.SilkS")
			(effects
				(font
					(size 0.7 0.7)
					(thickness 0.15)
				)
				(justify left bottom mirror)
			)
		)
		(property "Value" "R_10k_0402"
			(at 0 -1.4 0)
			(layer "B.Fab")
			(effects
				(font
					(size 0.7 0.7)
					(thickness 0.15)
				)
				(justify left bottom mirror)
			)
		)
		(property "Description" "SMD Chip Resistor, 10 kohm, ± 1%, 62.5 mW, 0402 [1005 Metric], Thick Film, General Purpose"
			(at 0 0 180)
			(layer "F.Fab")
			(hide yes)
			(effects
				(font
					(size 1.27 1.27)
					(thickness 0.15)
				)
			)
		)
		(property "Author" "Antmicro"
			(at 454.2 308.4 0)
			(layer "B.Fab")
			(hide yes)
			(effects
				(font
					(size 1 1)
					(thickness 0.15)
				)
				(justify mirror)
			)
		)
		(property "DNP" "DNP"
			(at 454.2 308.4 0)
			(layer "B.Fab")
			(hide yes)
			(effects
				(font
					(size 1 1)
					(thickness 0.15)
				)
				(justify mirror)
			)
		)
		(property "License" "Apache-2.0"
			(at 454.2 308.4 0)
			(layer "B.Fab")
			(hide yes)
			(effects
				(font
					(size 1 1)
					(thickness 0.15)
				)
				(justify mirror)
			)
		)
		(property "MPN" "CR0402-FX-1002GLF"
			(at 454.2 308.4 0)
			(layer "B.Fab")
			(hide yes)
			(effects
				(font
					(size 1 1)
					(thickness 0.15)
				)
				(justify mirror)
			)
		)
		(property "Manufacturer" "Bourns"
			(at 454.2 308.4 0)
			(layer "B.Fab")
			(hide yes)
			(effects
				(font
					(size 1 1)
					(thickness 0.15)
				)
				(justify mirror)
			)
		)
		(property "Tolerance" "1%"
			(at 454.2 308.4 0)
			(layer "B.Fab")
			(hide yes)
			(effects
				(font
					(size 1 1)
					(thickness 0.15)
				)
				(justify mirror)
			)
		)
		(property "Val" "10k"
			(at 454.2 308.4 0)
			(layer "B.Fab")
			(hide yes)
			(effects
				(font
					(size 1 1)
					(thickness 0.15)
				)
				(justify mirror)
			)
		)
		(property "dnp" ""
			(at 454.2 308.4 0)
			(layer "B.Fab")
			(hide yes)
			(effects
				(font
					(size 1 1)
					(thickness 0.15)
				)
				(justify mirror)
			)
		)
		(property "exclude_from_bom" ""
			(at 454.2 308.4 0)
			(layer "B.Fab")
			(hide yes)
			(effects
				(font
					(size 1 1)
					(thickness 0.15)
				)
				(justify mirror)
			)
		)
		(sheetname "HDMI + Ethernet")
		(sheetfile "hdmi-ethernet.kicad_sch")
		(attr smd exclude_from_bom)
		(fp_rect
			(start -0.925 0.47)
			(end 0.925 -0.47)
			(stroke
				(width 0.05)
				(type default)
			)
			(fill no)
			(layer "B.CrtYd")
		)
		(fp_rect
			(start -0.5 0.25)
			(end 0.5 -0.25)
			(stroke
				(width 0.15)
				(type solid)
			)
			(fill no)
			(layer "B.Fab")
		)
		(pad "1" smd roundrect
			(at -0.48 0 180)
			(size 0.59 0.64)
			(layers "B.Cu" "B.Mask" "B.Paste")
			(roundrect_rratio 0.25)
			(net 846 "/HDMI + Ethernet/ETH_LED_SPD-")
			(pintype "passive")
		)
		(pad "2" smd roundrect
			(at 0.48 0 180)
			(size 0.59 0.64)
			(layers "B.Cu" "B.Mask" "B.Paste")
			(roundrect_rratio 0.25)
			(net 26 "+1V8")
			(pintype "passive")
		)
	)
	(footprint "antmicro-footprints:C_0201"
		(layer "B.Cu")
		(at 193.5 127)
		(descr "Capacitor SMD 0201")
		(tags "capacitor SMD 0201")
		(property "Reference" "C126"
			(at 21.075 -29.15 0)
			(layer "B.SilkS")
			(effects
				(font
					(size 0.7 0.7)
					(thickness 0.15)
				)
				(justify right bottom mirror)
			)
		)
		(property "Value" "C_100n_0201"
			(at 0 -1.4 0)
			(layer "B.Fab")
			(effects
				(font
					(size 0.7 0.7)
					(thickness 0.15)
				)
				(justify right bottom mirror)
			)
		)
		(property "Description" "SMD Multilayer Ceramic Capacitor, 0.1 µF, 6.3 V, 0201 [0603 Metric], ± 10%, X6S, CC Series"
			(at 0 0 0)
			(layer "F.Fab")
			(hide yes)
			(effects
				(font
					(size 1.27 1.27)
					(thickness 0.15)
				)
			)
		)
		(property "Author" "Antmicro"
			(at 0 0 0)
			(layer "B.Fab")
			(hide yes)
			(effects
				(font
					(size 1 1)
					(thickness 0.15)
				)
				(justify mirror)
			)
		)
		(property "Dielectric" ""
			(at 0 0 0)
			(layer "B.Fab")
			(hide yes)
			(effects
				(font
					(size 1 1)
					(thickness 0.15)
				)
				(justify mirror)
			)
		)
		(property "License" "Apache-2.0"
			(at 0 0 0)
			(layer "B.Fab")
			(hide yes)
			(effects
				(font
					(size 1 1)
					(thickness 0.15)
				)
				(justify mirror)
			)
		)
		(property "MPN" "CC0201KRX6S5BB104"
			(at 0 0 0)
			(layer "B.Fab")
			(hide yes)
			(effects
				(font
					(size 1 1)
					(thickness 0.15)
				)
				(justify mirror)
			)
		)
		(property "Manufacturer" "YAGEO"
			(at 0 0 0)
			(layer "B.Fab")
			(hide yes)
			(effects
				(font
					(size 1 1)
					(thickness 0.15)
				)
				(justify mirror)
			)
		)
		(property "Val" "100n"
			(at 0 0 0)
			(layer "B.Fab")
			(hide yes)
			(effects
				(font
					(size 1 1)
					(thickness 0.15)
				)
				(justify mirror)
			)
		)
		(property "Voltage" ""
			(at 0 0 0)
			(layer "B.Fab")
			(hide yes)
			(effects
				(font
					(size 1 1)
					(thickness 0.15)
				)
				(justify mirror)
			)
		)
		(sheetname "FPGA supply")
		(sheetfile "fpga-supply.kicad_sch")
		(attr smd)
		(fp_rect
			(start -0.7 0.35)
			(end 0.7 -0.35)
			(stroke
				(width 0.05)
				(type default)
			)
			(fill no)
			(layer "B.CrtYd")
		)
		(fp_rect
			(start 0.3 -0.15)
			(end -0.301 0.149)
			(stroke
				(width 0.15)
				(type solid)
			)
			(fill no)
			(layer "B.Fab")
		)
		(pad "" smd roundrect
			(at -0.349 0.002)
			(size 0.318 0.36)
			(layers "B.Paste")
			(roundrect_rratio 0.25)
		)
		(pad "" smd roundrect
			(at 0.341 0.002)
			(size 0.318 0.36)
			(layers "B.Paste")
			(roundrect_rratio 0.25)
		)
		(pad "1" smd roundrect
			(at -0.321 0.002)
			(size 0.46 0.4)
			(layers "B.Cu" "B.Mask")
			(roundrect_rratio 0.25)
			(net 1 "GND")
			(pintype "passive")
		)
		(pad "2" smd roundrect
			(at 0.32 0.002)
			(size 0.46 0.4)
			(layers "B.Cu" "B.Mask")
			(roundrect_rratio 0.25)
			(net 650 "+1V0")
			(pintype "passive")
		)
	)
	(footprint "antmicro-footprints:C_0402_1005Metric"
		(layer "B.Cu")
		(at 208.5 116 -90)
		(descr "Capacitor SMD 0402")
		(tags "capacitor SMD 0402")
		(property "Reference" "C47"
			(at -1.1 -1.275 90)
			(layer "B.SilkS")
			(effects
				(font
					(size 0.7 0.7)
					(thickness 0.15)
				)
				(justify left bottom mirror)
			)
		)
		(property "Value" "C_100n_0402"
			(at 0 -1.169 90)
			(layer "B.Fab")
			(effects
				(font
					(size 0.7 0.7)
					(thickness 0.15)
				)
				(justify left bottom mirror)
			)
		)
		(property "Description" "SMD Multilayer Ceramic Capacitor, 0.1 µF, 50 V, 0402 [1005 Metric], ± 10%, X5R, GRM Series"
			(at 0 0 270)
			(layer "F.Fab")
			(hide yes)
			(effects
				(font
					(size 1.27 1.27)
					(thickness 0.15)
				)
			)
		)
		(property "Author" "Antmicro"
			(at 92.5 324.5 0)
			(layer "B.Fab")
			(hide yes)
			(effects
				(font
					(size 1 1)
					(thickness 0.15)
				)
				(justify mirror)
			)
		)
		(property "Dielectric" "X5R"
			(at 92.5 324.5 0)
			(layer "B.Fab")
			(hide yes)
			(effects
				(font
					(size 1 1)
					(thickness 0.15)
				)
				(justify mirror)
			)
		)
		(property "License" "Apache-2.0"
			(at 92.5 324.5 0)
			(layer "B.Fab")
			(hide yes)
			(effects
				(font
					(size 1 1)
					(thickness 0.15)
				)
				(justify mirror)
			)
		)
		(property "MPN" "GRM155R61H104KE14D"
			(at 92.5 324.5 0)
			(layer "B.Fab")
			(hide yes)
			(effects
				(font
					(size 1 1)
					(thickness 0.15)
				)
				(justify mirror)
			)
		)
		(property "Manufacturer" "Murata"
			(at 92.5 324.5 0)
			(layer "B.Fab")
			(hide yes)
			(effects
				(font
					(size 1 1)
					(thickness 0.15)
				)
				(justify mirror)
			)
		)
		(property "Val" "100n"
			(at 92.5 324.5 0)
			(layer "B.Fab")
			(hide yes)
			(effects
				(font
					(size 1 1)
					(thickness 0.15)
				)
				(justify mirror)
			)
		)
		(property "Voltage" "50V"
			(at 92.5 324.5 0)
			(layer "B.Fab")
			(hide yes)
			(effects
				(font
					(size 1 1)
					(thickness 0.15)
				)
				(justify mirror)
			)
		)
		(sheetname "FPGA Bank 16 & 17")
		(sheetfile "fpga-bank-16-17.kicad_sch")
		(attr smd)
		(fp_rect
			(start -0.925 0.47)
			(end 0.925 -0.47)
			(stroke
				(width 0.05)
				(type default)
			)
			(fill no)
			(layer "B.CrtYd")
		)
		(fp_line
			(start -0.494 0.25)
			(end 0.504 0.25)
			(stroke
				(width 0.15)
				(type solid)
			)
			(layer "B.Fab")
		)
		(fp_line
			(start 0.504 0.25)
			(end 0.504 -0.248)
			(stroke
				(width 0.15)
				(type solid)
			)
			(layer "B.Fab")
		)
		(fp_line
			(start -0.494 -0.248)
			(end -0.494 0.25)
			(stroke
				(width 0.15)
				(type solid)
			)
			(layer "B.Fab")
		)
		(fp_line
			(start 0.504 -0.248)
			(end -0.494 -0.248)
			(stroke
				(width 0.15)
				(type solid)
			)
			(layer "B.Fab")
		)
		(pad "1" smd roundrect
			(at -0.48 0 270)
			(size 0.59 0.64)
			(layers "B.Cu" "B.Mask" "B.Paste")
			(roundrect_rratio 0.25)
			(net 1 "GND")
			(pintype "passive")
		)
		(pad "2" smd roundrect
			(at 0.48 0 270)
			(size 0.59 0.64)
			(layers "B.Cu" "B.Mask" "B.Paste")
			(roundrect_rratio 0.25)
			(net 3 "VCC_USR_B")
			(pintype "passive")
		)
	)
	(footprint "antmicro-footprints:R_0402_1005Metric"
		(layer "B.Cu")
		(at 252.101 179.05 90)
		(descr "Resistor SMD 0402")
		(tags "resistor SMD 0402")
		(property "Reference" "R48"
			(at -0.775 0.374 270)
			(layer "B.SilkS")
			(effects
				(font
					(size 0.7 0.7)
					(thickness 0.15)
				)
				(justify left bottom mirror)
			)
		)
		(property "Value" "R_49k9_0402"
			(at 0 -1.4 270)
			(layer "B.Fab")
			(effects
				(font
					(size 0.7 0.7)
					(thickness 0.15)
				)
				(justify left bottom mirror)
			)
		)
		(property "Description" "SMD Chip Resistor, 49.9 kohm, ± 1%, 63 mW, 0402 [1005 Metric], Thick Film, General Purpose"
			(at 0 0 90)
			(layer "F.Fab")
			(hide yes)
			(effects
				(font
					(size 1.27 1.27)
					(thickness 0.15)
				)
			)
		)
		(property "Author" "Antmicro"
			(at 431.151 -73.051 0)
			(layer "B.Fab")
			(hide yes)
			(effects
				(font
					(size 1 1)
					(thickness 0.15)
				)
				(justify mirror)
			)
		)
		(property "License" "Apache-2.0"
			(at 431.151 -73.051 0)
			(layer "B.Fab")
			(hide yes)
			(effects
				(font
					(size 1 1)
					(thickness 0.15)
				)
				(justify mirror)
			)
		)
		(property "MPN" "CR0402-FX-4992GLF"
			(at 431.151 -73.051 0)
			(layer "B.Fab")
			(hide yes)
			(effects
				(font
					(size 1 1)
					(thickness 0.15)
				)
				(justify mirror)
			)
		)
		(property "Manufacturer" "Bourns"
			(at 431.151 -73.051 0)
			(layer "B.Fab")
			(hide yes)
			(effects
				(font
					(size 1 1)
					(thickness 0.15)
				)
				(justify mirror)
			)
		)
		(property "Tolerance" "1%"
			(at 431.151 -73.051 0)
			(layer "B.Fab")
			(hide yes)
			(effects
				(font
					(size 1 1)
					(thickness 0.15)
				)
				(justify mirror)
			)
		)
		(property "Val" "49k9"
			(at 431.151 -73.051 0)
			(layer "B.Fab")
			(hide yes)
			(effects
				(font
					(size 1 1)
					(thickness 0.15)
				)
				(justify mirror)
			)
		)
		(sheetname "Power supply")
		(sheetfile "power-supply.kicad_sch")
		(attr smd)
		(fp_rect
			(start -0.925 0.47)
			(end 0.925 -0.47)
			(stroke
				(width 0.05)
				(type default)
			)
			(fill no)
			(layer "B.CrtYd")
		)
		(fp_rect
			(start -0.5 0.25)
			(end 0.5 -0.25)
			(stroke
				(width 0.15)
				(type solid)
			)
			(fill no)
			(layer "B.Fab")
		)
		(pad "1" smd roundrect
			(at -0.48 0 90)
			(size 0.59 0.64)
			(layers "B.Cu" "B.Mask" "B.Paste")
			(roundrect_rratio 0.25)
			(net 697 "/Power supply/VSS")
			(pintype "passive")
		)
		(pad "2" smd roundrect
			(at 0.48 0 90)
			(size 0.59 0.64)
			(layers "B.Cu" "B.Mask" "B.Paste")
			(roundrect_rratio 0.25)
			(net 882 "/Power supply/REF")
			(pintype "passive")
		)
	)
)
